(kicad_pcb
	(version 20240108)
	(generator "pcbnew")
	(generator_version "8.0")
	(general
		(thickness 1.62)
		(legacy_teardrops no)
	)
	(paper "A4")
	(title_block
		(title "Jetson Orin Baseboard")
		(date "2025-03-12")
		(rev "1.3.4")
		(company "Antmicro Ltd")
		(comment 1 "www.antmicro.com")
		(comment 9 "footprints 367-371 of 677")
	)
	(layers
		(0 "F.Cu" signal)
		(1 "In1.Cu" signal)
		(2 "In2.Cu" signal)
		(3 "In3.Cu" signal)
		(4 "In4.Cu" jumper)
		(5 "In5.Cu" signal)
		(6 "In6.Cu" signal)
		(31 "B.Cu" signal)
		(32 "B.Adhes" user "B.Adhesive")
		(33 "F.Adhes" user "F.Adhesive")
		(34 "B.Paste" user)
		(35 "F.Paste" user)
		(36 "B.SilkS" user "B.Silkscreen")
		(37 "F.SilkS" user "F.Silkscreen")
		(38 "B.Mask" user)
		(39 "F.Mask" user)
		(40 "Dwgs.User" user "User.Drawings")
		(41 "Cmts.User" user "User.Comments")
		(42 "Eco1.User" user "User.Eco1")
		(43 "Eco2.User" user "User.Eco2")
		(44 "Edge.Cuts" user)
		(45 "Margin" user)
		(46 "B.CrtYd" user "B.Courtyard")
		(47 "F.CrtYd" user "F.Courtyard")
		(48 "B.Fab" user)
		(49 "F.Fab" user)
	)
	(footprint "antmicro-footprints:R_Array_4x0201_Panasonic_EXB18V"
		(layer "B.Cu")
		(at 112.22 74.63 90)
		(property "Reference" "R108"
			(at -1.52 -0.67 -90)
			(layer "B.SilkS")
			(effects
				(font
					(size 0.7 0.7)
					(thickness 0.15)
				)
				(justify right bottom mirror)
			)
		)
		(property "Value" "R_4x0R_0201_array"
			(at -1.1 -1.8 -90)
			(layer "B.Fab")
			(effects
				(font
					(size 0.7 0.7)
					(thickness 0.15)
				)
				(justify left bottom mirror)
			)
		)
		(property "Footprint" "antmicro-footprints:R_Array_4x0201_Panasonic_EXB18V"
			(at 0 0 90)
			(layer "F.Fab")
			(hide yes)
			(effects
				(font
					(size 1.27 1.27)
					(thickness 0.15)
				)
			)
		)
		(property "Datasheet" "http://industrial.panasonic.com/cdbs/www-data/pdf/AOC0000/AOC0000C14.pdf"
			(at 0 0 90)
			(layer "F.Fab")
			(hide yes)
			(effects
				(font
					(size 1.27 1.27)
					(thickness 0.15)
				)
			)
		)
		(property "Author" "Antmicro"
			(at 186.85 -37.59 0)
			(layer "B.Fab")
			(hide yes)
			(effects
				(font
					(size 1 1)
					(thickness 0.15)
				)
				(justify mirror)
			)
		)
		(property "License" "Apache-2.0"
			(at 186.85 -37.59 0)
			(layer "B.Fab")
			(hide yes)
			(effects
				(font
					(size 1 1)
					(thickness 0.15)
				)
				(justify mirror)
			)
		)
		(property "MPN" "EXB-18VR000X"
			(at 186.85 -37.59 0)
			(layer "B.Fab")
			(hide yes)
			(effects
				(font
					(size 1 1)
					(thickness 0.15)
				)
				(justify mirror)
			)
		)
		(property "Manufacturer" "Panasonic"
			(at 186.85 -37.59 0)
			(layer "B.Fab")
			(hide yes)
			(effects
				(font
					(size 1 1)
					(thickness 0.15)
				)
				(justify mirror)
			)
		)
		(property "Val" "4x0R_0201"
			(at 186.85 -37.59 0)
			(layer "B.Fab")
			(hide yes)
			(effects
				(font
					(size 1 1)
					(thickness 0.15)
				)
				(justify mirror)
			)
		)
		(sheetname "CSI")
		(sheetfile "csi.kicad_sch")
		(attr smd)
		(fp_line
			(start 0.8 -0.45)
			(end 0.8 0.45)
			(stroke
				(width 0.12)
				(type solid)
			)
			(layer "B.SilkS")
		)
		(fp_line
			(start -0.8 -0.45)
			(end -0.8 0.45)
			(stroke
				(width 0.12)
				(type solid)
			)
			(layer "B.SilkS")
		)
		(fp_rect
			(start -0.898 0.66)
			(end 0.898 -0.65)
			(stroke
				(width 0.05)
				(type solid)
			)
			(fill none)
			(layer "B.CrtYd")
		)
		(fp_text user "License: Apache-2.0"
			(at -1.051 -6 -90)
			(layer "B.Fab")
			(hide yes)
			(effects
				(font
					(size 0.7 0.7)
					(thickness 0.15)
				)
				(justify left bottom mirror)
			)
		)
		(fp_text user "Author: Antmicro"
			(at -1.051 -4.599 -90)
			(layer "B.Fab")
			(hide yes)
			(effects
				(font
					(size 0.7 0.7)
					(thickness 0.15)
				)
				(justify left bottom mirror)
			)
		)
		(fp_text user "${REFERENCE}"
			(at -1.051 -3.2 -90)
			(layer "B.Fab")
			(hide yes)
			(effects
				(font
					(size 0.7 0.7)
					(thickness 0.15)
				)
				(justify left bottom mirror)
			)
		)
		(pad "1" smd roundrect
			(at -0.6 -0.298 90)
			(size 0.2 0.4)
			(layers "B.Cu" "B.Paste" "B.Mask")
			(roundrect_rratio 0.25)
			(net 14 "CSI3_D0_N")
			(pinfunction "R1.1")
			(pintype "passive")
		)
		(pad "2" smd roundrect
			(at -0.202 -0.298 90)
			(size 0.2 0.4)
			(layers "B.Cu" "B.Paste" "B.Mask")
			(roundrect_rratio 0.25)
			(net 16 "CSI3_D0_P")
			(pinfunction "R2.1")
			(pintype "passive")
		)
		(pad "3" smd roundrect
			(at 0.2 -0.298 90)
			(size 0.2 0.4)
			(layers "B.Cu" "B.Paste" "B.Mask")
			(roundrect_rratio 0.25)
			(net 22 "CSI3_D1_N")
			(pinfunction "R3.1")
			(pintype "passive")
		)
		(pad "4" smd roundrect
			(at 0.598 -0.298 90)
			(size 0.2 0.4)
			(layers "B.Cu" "B.Paste" "B.Mask")
			(roundrect_rratio 0.25)
			(net 24 "CSI3_D1_P")
			(pinfunction "R4.1")
			(pintype "passive")
		)
		(pad "5" smd roundrect
			(at 0.598 0.3 90)
			(size 0.2 0.4)
			(layers "B.Cu" "B.Paste" "B.Mask")
			(roundrect_rratio 0.25)
			(net 213 "/CSI/CSI3_0_D1_P")
			(pinfunction "R4.2")
			(pintype "passive")
		)
		(pad "6" smd roundrect
			(at 0.2 0.3 90)
			(size 0.2 0.4)
			(layers "B.Cu" "B.Paste" "B.Mask")
			(roundrect_rratio 0.25)
			(net 212 "/CSI/CSI3_0_D1_N")
			(pinfunction "R3.2")
			(pintype "passive")
		)
		(pad "7" smd roundrect
			(at -0.202 0.3 90)
			(size 0.2 0.4)
			(layers "B.Cu" "B.Paste" "B.Mask")
			(roundrect_rratio 0.25)
			(net 215 "/CSI/CSI3_0_D0_P")
			(pinfunction "R2.2")
			(pintype "passive")
		)
		(pad "8" smd roundrect
			(at -0.6 0.3 90)
			(size 0.2 0.4)
			(layers "B.Cu" "B.Paste" "B.Mask")
			(roundrect_rratio 0.25)
			(net 214 "/CSI/CSI3_0_D0_N")
			(pinfunction "R1.2")
			(pintype "passive")
		)
	)
	(footprint "antmicro-footprints:R_0402_1005Metric"
		(layer "B.Cu")
		(at 138.8 122)
		(descr "Resistor SMD 0402")
		(tags "resistor SMD 0402")
		(property "Reference" "R192"
			(at 1.11 -1.35 180)
			(layer "B.SilkS")
			(effects
				(font
					(size 0.7 0.7)
					(thickness 0.15)
				)
				(justify left bottom mirror)
			)
		)
		(property "Value" "R_100k_0402"
			(at 0 -1.4 180)
			(layer "B.Fab")
			(effects
				(font
					(size 0.7 0.7)
					(thickness 0.15)
				)
				(justify left bottom mirror)
			)
		)
		(property "Footprint" "antmicro-footprints:R_0402_1005Metric"
			(at 0 0 0)
			(layer "F.Fab")
			(hide yes)
			(effects
				(font
					(size 1.27 1.27)
					(thickness 0.15)
				)
			)
		)
		(property "Datasheet" "https://www.bourns.com/docs/product-datasheets/cr.pdf"
			(at 0 0 0)
			(layer "F.Fab")
			(hide yes)
			(effects
				(font
					(size 1.27 1.27)
					(thickness 0.15)
				)
			)
		)
		(property "Author" "Antmicro"
			(at 0 0 0)
			(layer "B.Fab")
			(hide yes)
			(effects
				(font
					(size 1 1)
					(thickness 0.15)
				)
				(justify mirror)
			)
		)
		(property "License" "Apache-2.0"
			(at 0 0 0)
			(layer "B.Fab")
			(hide yes)
			(effects
				(font
					(size 1 1)
					(thickness 0.15)
				)
				(justify mirror)
			)
		)
		(property "MPN" "CR0402-FX-1003GLF"
			(at 0 0 0)
			(layer "B.Fab")
			(hide yes)
			(effects
				(font
					(size 1 1)
					(thickness 0.15)
				)
				(justify mirror)
			)
		)
		(property "Manufacturer" "Bourns"
			(at 0 0 0)
			(layer "B.Fab")
			(hide yes)
			(effects
				(font
					(size 1 1)
					(thickness 0.15)
				)
				(justify mirror)
			)
		)
		(property "Tolerance" "1%"
			(at 0 0 0)
			(layer "B.Fab")
			(hide yes)
			(effects
				(font
					(size 1 1)
					(thickness 0.15)
				)
				(justify mirror)
			)
		)
		(property "Val" "100k"
			(at 0 0 0)
			(layer "B.Fab")
			(hide yes)
			(effects
				(font
					(size 1 1)
					(thickness 0.15)
				)
				(justify mirror)
			)
		)
		(sheetname "Peripherals")
		(sheetfile "peripherals.kicad_sch")
		(attr smd exclude_from_pos_files exclude_from_bom dnp)
		(fp_rect
			(start -0.925 0.47)
			(end 0.925 -0.47)
			(stroke
				(width 0.05)
				(type default)
			)
			(fill none)
			(layer "B.CrtYd")
		)
		(fp_rect
			(start -0.5 0.25)
			(end 0.5 -0.25)
			(stroke
				(width 0.15)
				(type solid)
			)
			(fill none)
			(layer "B.Fab")
		)
		(fp_text user "License: Apache-2.0"
			(at -0.95 -5.169 180)
			(layer "B.Fab")
			(hide yes)
			(effects
				(font
					(size 0.7 0.7)
					(thickness 0.15)
				)
				(justify left bottom mirror)
			)
		)
		(fp_text user "${REFERENCE}"
			(at -0.95 -3.168 180)
			(layer "B.Fab")
			(hide yes)
			(effects
				(font
					(size 0.7 0.7)
					(thickness 0.15)
				)
				(justify left bottom mirror)
			)
		)
		(fp_text user "Author: Antmicro"
			(at -0.95 -4.169 180)
			(layer "B.Fab")
			(hide yes)
			(effects
				(font
					(size 0.7 0.7)
					(thickness 0.15)
				)
				(justify left bottom mirror)
			)
		)
		(pad "1" smd roundrect
			(at -0.48 0)
			(size 0.59 0.64)
			(layers "B.Cu" "B.Paste" "B.Mask")
			(roundrect_rratio 0.25)
			(net 1 "GND")
			(pintype "passive")
		)
		(pad "2" smd roundrect
			(at 0.48 0)
			(size 0.59 0.64)
			(layers "B.Cu" "B.Paste" "B.Mask")
			(roundrect_rratio 0.25)
			(net 658 "/Peripherals/I2C_CONN_PEN")
			(pintype "passive")
		)
	)
	(footprint "antmicro-footprints:R_0402_1005Metric"
		(layer "B.Cu")
		(at 69.6 94.4 -90)
		(descr "Resistor SMD 0402")
		(tags "resistor SMD 0402")
		(property "Reference" "R81"
			(at -1.15 -2.32 90)
			(layer "B.SilkS")
			(effects
				(font
					(size 0.7 0.7)
					(thickness 0.15)
				)
				(justify left bottom mirror)
			)
		)
		(property "Value" "R_4k7_0402"
			(at 0 -1.4 90)
			(layer "B.Fab")
			(effects
				(font
					(size 0.7 0.7)
					(thickness 0.15)
				)
				(justify left bottom mirror)
			)
		)
		(property "Footprint" "antmicro-footprints:R_0402_1005Metric"
			(at 0 0 -90)
			(layer "F.Fab")
			(hide yes)
			(effects
				(font
					(size 1.27 1.27)
					(thickness 0.15)
				)
			)
		)
		(property "Datasheet" "https://www.bourns.com/docs/product-datasheets/cr.pdf"
			(at 0 0 -90)
			(layer "F.Fab")
			(hide yes)
			(effects
				(font
					(size 1.27 1.27)
					(thickness 0.15)
				)
			)
		)
		(property "Author" "Antmicro"
			(at -24.8 164 0)
			(layer "B.Fab")
			(hide yes)
			(effects
				(font
					(size 1 1)
					(thickness 0.15)
				)
				(justify mirror)
			)
		)
		(property "License" "Apache-2.0"
			(at -24.8 164 0)
			(layer "B.Fab")
			(hide yes)
			(effects
				(font
					(size 1 1)
					(thickness 0.15)
				)
				(justify mirror)
			)
		)
		(property "MPN" "CR0402-FX-4701GLF"
			(at -24.8 164 0)
			(layer "B.Fab")
			(hide yes)
			(effects
				(font
					(size 1 1)
					(thickness 0.15)
				)
				(justify mirror)
			)
		)
		(property "Manufacturer" "Bourns"
			(at -24.8 164 0)
			(layer "B.Fab")
			(hide yes)
			(effects
				(font
					(size 1 1)
					(thickness 0.15)
				)
				(justify mirror)
			)
		)
		(property "Tolerance" "1%"
			(at -24.8 164 0)
			(layer "B.Fab")
			(hide yes)
			(effects
				(font
					(size 1 1)
					(thickness 0.15)
				)
				(justify mirror)
			)
		)
		(property "Val" "4k7"
			(at -24.8 164 0)
			(layer "B.Fab")
			(hide yes)
			(effects
				(font
					(size 1 1)
					(thickness 0.15)
				)
				(justify mirror)
			)
		)
		(sheetname "USB Debug, DP")
		(sheetfile "usb.kicad_sch")
		(attr smd)
		(fp_rect
			(start -0.925 0.47)
			(end 0.925 -0.47)
			(stroke
				(width 0.05)
				(type default)
			)
			(fill none)
			(layer "B.CrtYd")
		)
		(fp_rect
			(start -0.5 0.25)
			(end 0.5 -0.25)
			(stroke
				(width 0.15)
				(type solid)
			)
			(fill none)
			(layer "B.Fab")
		)
		(fp_text user "License: Apache-2.0"
			(at -0.95 -5.169 90)
			(layer "B.Fab")
			(hide yes)
			(effects
				(font
					(size 0.7 0.7)
					(thickness 0.15)
				)
				(justify left bottom mirror)
			)
		)
		(fp_text user "${REFERENCE}"
			(at -0.95 -3.168 90)
			(layer "B.Fab")
			(hide yes)
			(effects
				(font
					(size 0.7 0.7)
					(thickness 0.15)
				)
				(justify left bottom mirror)
			)
		)
		(fp_text user "Author: Antmicro"
			(at -0.95 -4.169 90)
			(layer "B.Fab")
			(hide yes)
			(effects
				(font
					(size 0.7 0.7)
					(thickness 0.15)
				)
				(justify left bottom mirror)
			)
		)
		(pad "1" smd roundrect
			(at -0.48 0 270)
			(size 0.59 0.64)
			(layers "B.Cu" "B.Paste" "B.Mask")
			(roundrect_rratio 0.25)
			(net 87 "+3V3")
			(pintype "passive")
		)
		(pad "2" smd roundrect
			(at 0.48 0 270)
			(size 0.59 0.64)
			(layers "B.Cu" "B.Paste" "B.Mask")
			(roundrect_rratio 0.25)
			(net 396 "/USB Debug, DP/PDC_I2C2_SDA")
			(pintype "passive")
		)
	)
	(footprint "antmicro-footprints:R_0402_1005Metric"
		(layer "B.Cu")
		(at 64.925 110.275 90)
		(descr "Resistor SMD 0402")
		(tags "resistor SMD 0402")
		(property "Reference" "R45"
			(at -0.845 0.365 -90)
			(layer "B.SilkS")
			(effects
				(font
					(size 0.7 0.7)
					(thickness 0.15)
				)
				(justify left bottom mirror)
			)
		)
		(property "Value" "R_100k_0402"
			(at 0 -1.4 -90)
			(layer "B.Fab")
			(effects
				(font
					(size 0.7 0.7)
					(thickness 0.15)
				)
				(justify left bottom mirror)
			)
		)
		(property "Footprint" "antmicro-footprints:R_0402_1005Metric"
			(at 0 0 90)
			(layer "F.Fab")
			(hide yes)
			(effects
				(font
					(size 1.27 1.27)
					(thickness 0.15)
				)
			)
		)
		(property "Datasheet" "https://www.bourns.com/docs/product-datasheets/cr.pdf"
			(at 0 0 90)
			(layer "F.Fab")
			(hide yes)
			(effects
				(font
					(size 1.27 1.27)
					(thickness 0.15)
				)
			)
		)
		(property "Author" "Antmicro"
			(at 175.2 45.35 0)
			(layer "B.Fab")
			(hide yes)
			(effects
				(font
					(size 1 1)
					(thickness 0.15)
				)
				(justify mirror)
			)
		)
		(property "License" "Apache-2.0"
			(at 175.2 45.35 0)
			(layer "B.Fab")
			(hide yes)
			(effects
				(font
					(size 1 1)
					(thickness 0.15)
				)
				(justify mirror)
			)
		)
		(property "MPN" "CR0402-FX-1003GLF"
			(at 175.2 45.35 0)
			(layer "B.Fab")
			(hide yes)
			(effects
				(font
					(size 1 1)
					(thickness 0.15)
				)
				(justify mirror)
			)
		)
		(property "Manufacturer" "Bourns"
			(at 175.2 45.35 0)
			(layer "B.Fab")
			(hide yes)
			(effects
				(font
					(size 1 1)
					(thickness 0.15)
				)
				(justify mirror)
			)
		)
		(property "Tolerance" "1%"
			(at 175.2 45.35 0)
			(layer "B.Fab")
			(hide yes)
			(effects
				(font
					(size 1 1)
					(thickness 0.15)
				)
				(justify mirror)
			)
		)
		(property "Val" "100k"
			(at 175.2 45.35 0)
			(layer "B.Fab")
			(hide yes)
			(effects
				(font
					(size 1 1)
					(thickness 0.15)
				)
				(justify mirror)
			)
		)
		(sheetname "USB Debug, DP")
		(sheetfile "usb.kicad_sch")
		(attr smd)
		(fp_rect
			(start -0.925 0.47)
			(end 0.925 -0.47)
			(stroke
				(width 0.05)
				(type default)
			)
			(fill none)
			(layer "B.CrtYd")
		)
		(fp_rect
			(start -0.5 0.25)
			(end 0.5 -0.25)
			(stroke
				(width 0.15)
				(type solid)
			)
			(fill none)
			(layer "B.Fab")
		)
		(fp_text user "License: Apache-2.0"
			(at -0.95 -5.169 -90)
			(layer "B.Fab")
			(hide yes)
			(effects
				(font
					(size 0.7 0.7)
					(thickness 0.15)
				)
				(justify left bottom mirror)
			)
		)
		(fp_text user "${REFERENCE}"
			(at -0.95 -3.168 -90)
			(layer "B.Fab")
			(hide yes)
			(effects
				(font
					(size 0.7 0.7)
					(thickness 0.15)
				)
				(justify left bottom mirror)
			)
		)
		(fp_text user "Author: Antmicro"
			(at -0.95 -4.169 -90)
			(layer "B.Fab")
			(hide yes)
			(effects
				(font
					(size 0.7 0.7)
					(thickness 0.15)
				)
				(justify left bottom mirror)
			)
		)
		(pad "1" smd roundrect
			(at -0.48 0 90)
			(size 0.59 0.64)
			(layers "B.Cu" "B.Paste" "B.Mask")
			(roundrect_rratio 0.25)
			(net 1 "GND")
			(pintype "passive")
		)
		(pad "2" smd roundrect
			(at 0.48 0 90)
			(size 0.59 0.64)
			(layers "B.Cu" "B.Paste" "B.Mask")
			(roundrect_rratio 0.25)
			(net 287 "/USB Debug, DP/PDC_ADCIN2")
			(pintype "passive")
		)
	)
	(footprint "antmicro-footprints:C_0402_1005Metric"
		(layer "B.Cu")
		(at 106.4 87.87 90)
		(descr "Capacitor SMD 0402")
		(tags "capacitor SMD 0402")
		(property "Reference" "C7"
			(at 0.67 -0.45 -90)
			(layer "B.SilkS")
			(effects
				(font
					(size 0.7 0.7)
					(thickness 0.15)
				)
				(justify left bottom mirror)
			)
		)
		(property "Value" "C_100n_0402"
			(at 0 -1.4 -90)
			(layer "B.Fab")
			(effects
				(font
					(size 0.7 0.7)
					(thickness 0.15)
				)
				(justify left bottom mirror)
			)
		)
		(property "Footprint" "antmicro-footprints:C_0402_1005Metric"
			(at 0 0 90)
			(layer "F.Fab")
			(hide yes)
			(effects
				(font
					(size 1.27 1.27)
					(thickness 0.15)
				)
			)
		)
		(property "Datasheet" "https://www.murata.com/products/productdetail?partno=GRM155R61H104KE14%23"
			(at 0 0 90)
			(layer "F.Fab")
			(hide yes)
			(effects
				(font
					(size 1.27 1.27)
					(thickness 0.15)
				)
			)
		)
		(property "Author" "Antmicro"
			(at 194.27 -18.53 0)
			(layer "B.Fab")
			(hide yes)
			(effects
				(font
					(size 1 1)
					(thickness 0.15)
				)
				(justify mirror)
			)
		)
		(property "Dielectric" "X5R"
			(at 194.27 -18.53 0)
			(layer "B.Fab")
			(hide yes)
			(effects
				(font
					(size 1 1)
					(thickness 0.15)
				)
				(justify mirror)
			)
		)
		(property "License" "Apache-2.0"
			(at 194.27 -18.53 0)
			(layer "B.Fab")
			(hide yes)
			(effects
				(font
					(size 1 1)
					(thickness 0.15)
				)
				(justify mirror)
			)
		)
		(property "MPN" "GRM155R61H104KE14D"
			(at 194.27 -18.53 0)
			(layer "B.Fab")
			(hide yes)
			(effects
				(font
					(size 1 1)
					(thickness 0.15)
				)
				(justify mirror)
			)
		)
		(property "Manufacturer" "Murata"
			(at 194.27 -18.53 0)
			(layer "B.Fab")
			(hide yes)
			(effects
				(font
					(size 1 1)
					(thickness 0.15)
				)
				(justify mirror)
			)
		)
		(property "Val" "100n"
			(at 194.27 -18.53 0)
			(layer "B.Fab")
			(hide yes)
			(effects
				(font
					(size 1 1)
					(thickness 0.15)
				)
				(justify mirror)
			)
		)
		(property "Voltage" "50V"
			(at 194.27 -18.53 0)
			(layer "B.Fab")
			(hide yes)
			(effects
				(font
					(size 1 1)
					(thickness 0.15)
				)
				(justify mirror)
			)
		)
		(sheetname "M.2")
		(sheetfile "m-2.kicad_sch")
		(attr smd)
		(fp_rect
			(start -0.925 0.47)
			(end 0.925 -0.47)
			(stroke
				(width 0.05)
				(type default)
			)
			(fill none)
			(layer "B.CrtYd")
		)
		(fp_line
			(start 0.504 -0.248)
			(end 0.504 0.25)
			(stroke
				(width 0.15)
				(type solid)
			)
			(layer "B.Fab")
		)
		(fp_line
			(start -0.494 -0.248)
			(end 0.504 -0.248)
			(stroke
				(width 0.15)
				(type solid)
			)
			(layer "B.Fab")
		)
		(fp_line
			(start 0.504 0.25)
			(end -0.494 0.25)
			(stroke
				(width 0.15)
				(type solid)
			)
			(layer "B.Fab")
		)
		(fp_line
			(start -0.494 0.25)
			(end -0.494 -0.248)
			(stroke
				(width 0.15)
				(type solid)
			)
			(layer "B.Fab")
		)
		(fp_text user "Author: Antmicro"
			(at -0.932 -4.17 -90)
			(layer "B.Fab")
			(hide yes)
			(effects
				(font
					(size 0.7 0.7)
					(thickness 0.15)
				)
				(justify left bottom mirror)
			)
		)
		(fp_text user "License: Apache-2.0"
			(at -0.932 -5.17 -90)
			(layer "B.Fab")
			(hide yes)
			(effects
				(font
					(size 0.7 0.7)
					(thickness 0.15)
				)
				(justify left bottom mirror)
			)
		)
		(fp_text user "${REFERENCE}"
			(at -0.932 -3.168 -90)
			(layer "B.Fab")
			(hide yes)
			(effects
				(font
					(size 0.7 0.7)
					(thickness 0.15)
				)
				(justify left bottom mirror)
			)
		)
		(pad "1" smd roundrect
			(at -0.48 0 90)
			(size 0.59 0.64)
			(layers "B.Cu" "B.Paste" "B.Mask")
			(roundrect_rratio 0.25)
			(net 87 "+3V3")
			(pintype "passive")
		)
		(pad "2" smd roundrect
			(at 0.48 0 90)
			(size 0.59 0.64)
			(layers "B.Cu" "B.Paste" "B.Mask")
			(roundrect_rratio 0.25)
			(net 1 "GND")
			(pintype "passive")
		)
	)
)
